# S9S_MB_2U (Grand Teton) — schematic netlist excerpt (pin names and nets, part order shuffled) for the footprints in the layout excerpt that follows; sources: Cadence DE-HDL packaged netlist, KiCad conversion of 03242023_DA0F0TMBIJ0_F0T_Motherboard_J_brd_V01_OCP.brd

R4795  Q_RES  160K 1% EMPTY  pkg 0402LF  page 306 : A = HSC_CSOUT ; B = HSC_OC_VOL
R4043  Q_RES  33.2 1% CHIP  pkg 0402LF  page 225 : A = RST_CPU0_DRAM_CD_PLD_LVT3_R_N ; B = RST_CPU0_DRAM_CD_PLD_LVT3_N

(kicad_pcb
	(version 20260206)
	(generator "pcbnew")
	(generator_version "10.0")
	(general
		(thickness 1.6)
		(legacy_teardrops no)
	)
	(paper "A4")
	(title_block
		(title "03242023_DA0F0TMBIJ0_F0T_Motherboard_J_brd_V01_OCP.brd")
		(comment 1 "Grand Teton / footprints 4101-4102 of 6105")
	)
	(layers
		(0 "F.Cu" signal "TOP")
		(4 "In1.Cu" signal "GND")
		(6 "In2.Cu" signal "IN1")
		(8 "In3.Cu" signal "GND1")
		(10 "In4.Cu" signal "IN2")
		(12 "In5.Cu" signal "GND2")
		(14 "In6.Cu" signal "IN3")
		(16 "In7.Cu" signal "GND3")
		(18 "In8.Cu" signal "VCC")
		(20 "In9.Cu" signal "VCC1")
		(22 "In10.Cu" signal "GND4")
		(24 "In11.Cu" signal "IN4")
		(26 "In12.Cu" signal "GND5")
		(28 "In13.Cu" signal "IN5")
		(30 "In14.Cu" signal "GND6")
		(32 "In15.Cu" signal "IN6")
		(34 "In16.Cu" signal "GND7")
		(2 "B.Cu" signal "BOTTOM")
		(9 "F.Adhes" user "F.Adhesive")
		(11 "B.Adhes" user "B.Adhesive")
		(13 "F.Paste" user "Package Geometry/Pastemask Top")
		(15 "B.Paste" user "Package Geometry/Pastemask Bottom")
		(5 "F.SilkS" user "Ref Des/Silkscreen Top")
		(7 "B.SilkS" user "Ref Des/Silkscreen Bottom")
		(1 "F.Mask" user "Board Geometry/Soldermask Top")
		(3 "B.Mask" user "Board Geometry/Soldermask Bottom")
		(17 "Dwgs.User" user "User.Drawings")
		(19 "Cmts.User" user "User.Comments")
		(21 "Eco1.User" user "User.Eco1")
		(23 "Eco2.User" user "User.Eco2")
		(25 "Edge.Cuts" user "Board Geometry/Outline")
		(27 "Margin" user)
		(31 "F.CrtYd" user "Package Geometry/Place Bound Top")
		(29 "B.CrtYd" user "Package Geometry/Place Bound Bottom")
		(35 "F.Fab" user "Ref Des/Assembly Top")
		(33 "B.Fab" user "Ref Des/Assembly Bottom")
	)
	(footprint ""
		(layer "F.Cu")
		(at 183.54802 -419.47338 90)
		(property "Reference" "R4795"
			(at 0 0 90)
			(layer "F.SilkS")
			(hide yes)
			(effects
				(font
					(size 1.27 1.27)
				)
			)
		)
		(property "Value" ""
			(at 0 0 90)
			(layer "F.Fab")
			(effects
				(font
					(size 1.27 1.27)
				)
			)
		)
		(duplicate_pad_numbers_are_jumpers no)
		(fp_line
			(start 0.7874 -0.4064)
			(end 0.7874 0.4064)
			(stroke
				(width 0.1524)
				(type default)
			)
			(layer "F.SilkS")
		)
		(fp_line
			(start -0.7874 -0.4064)
			(end 0.7874 -0.4064)
			(stroke
				(width 0.1524)
				(type default)
			)
			(layer "F.SilkS")
		)
		(fp_line
			(start 0.7874 0.4064)
			(end -0.7874 0.4064)
			(stroke
				(width 0.1524)
				(type default)
			)
			(layer "F.SilkS")
		)
		(fp_line
			(start -0.7874 0.4064)
			(end -0.7874 -0.4064)
			(stroke
				(width 0.1524)
				(type default)
			)
			(layer "F.SilkS")
		)
		(fp_line
			(start -0.12065 -0.305054)
			(end -0.12065 -0.2794)
			(stroke
				(width 0.1)
				(type default)
			)
			(layer "F.Fab")
		)
		(fp_line
			(start -0.67945 -0.305054)
			(end -0.12065 -0.305054)
			(stroke
				(width 0.1)
				(type default)
			)
			(layer "F.Fab")
		)
		(fp_line
			(start 0.67945 -0.3048)
			(end 0.67945 0.3048)
			(stroke
				(width 0.1)
				(type default)
			)
			(layer "F.Fab")
		)
		(fp_line
			(start 0.12065 -0.3048)
			(end 0.67945 -0.3048)
			(stroke
				(width 0.1)
				(type default)
			)
			(layer "F.Fab")
		)
		(fp_line
			(start 0.12065 -0.2794)
			(end 0.12065 -0.3048)
			(stroke
				(width 0.1)
				(type default)
			)
			(layer "F.Fab")
		)
		(fp_line
			(start -0.12065 -0.2794)
			(end 0.12065 -0.2794)
			(stroke
				(width 0.1)
				(type default)
			)
			(layer "F.Fab")
		)
		(fp_line
			(start 0.120396 0.2794)
			(end -0.12065 0.2794)
			(stroke
				(width 0.1)
				(type default)
			)
			(layer "F.Fab")
		)
		(fp_line
			(start -0.12065 0.2794)
			(end -0.12065 0.3048)
			(stroke
				(width 0.1)
				(type default)
			)
			(layer "F.Fab")
		)
		(fp_line
			(start 0.67945 0.3048)
			(end 0.120396 0.3048)
			(stroke
				(width 0.1)
				(type default)
			)
			(layer "F.Fab")
		)
		(fp_line
			(start 0.120396 0.3048)
			(end 0.120396 0.2794)
			(stroke
				(width 0.1)
				(type default)
			)
			(layer "F.Fab")
		)
		(fp_line
			(start -0.12065 0.3048)
			(end -0.67945 0.3048)
			(stroke
				(width 0.1)
				(type default)
			)
			(layer "F.Fab")
		)
		(fp_line
			(start -0.67945 0.3048)
			(end -0.67945 -0.305054)
			(stroke
				(width 0.1)
				(type default)
			)
			(layer "F.Fab")
		)
		(pad "1" smd circle
			(at -0.40005 0 90)
			(size 0 0)
			(layers "F.Cu" "F.Mask" "F.Paste")
			(net "HSC_CSOUT")
		)
		(pad "2" smd circle
			(at 0.40005 0 90)
			(size 0 0)
			(layers "F.Cu" "F.Mask" "F.Paste")
			(net "HSC_OC_VOL")
		)
	)
	(footprint ""
		(layer "F.Cu")
		(at 113.92408 -106.238548 -90)
		(property "Reference" "R4043"
			(at 0 0 270)
			(layer "F.SilkS")
			(hide yes)
			(effects
				(font
					(size 1.27 1.27)
				)
			)
		)
		(property "Value" ""
			(at 0 0 270)
			(layer "F.Fab")
			(effects
				(font
					(size 1.27 1.27)
				)
			)
		)
		(duplicate_pad_numbers_are_jumpers no)
		(fp_line
			(start -0.7874 0.4064)
			(end -0.7874 -0.4064)
			(stroke
				(width 0.1524)
				(type default)
			)
			(layer "F.SilkS")
		)
		(fp_line
			(start 0.7874 0.4064)
			(end -0.7874 0.4064)
			(stroke
				(width 0.1524)
				(type default)
			)
			(layer "F.SilkS")
		)
		(fp_line
			(start -0.7874 -0.4064)
			(end 0.7874 -0.4064)
			(stroke
				(width 0.1524)
				(type default)
			)
			(layer "F.SilkS")
		)
		(fp_line
			(start 0.7874 -0.4064)
			(end 0.7874 0.4064)
			(stroke
				(width 0.1524)
				(type default)
			)
			(layer "F.SilkS")
		)
		(fp_line
			(start -0.67945 0.3048)
			(end -0.67945 -0.305054)
			(stroke
				(width 0.1)
				(type default)
			)
			(layer "F.Fab")
		)
		(fp_line
			(start -0.12065 0.3048)
			(end -0.67945 0.3048)
			(stroke
				(width 0.1)
				(type default)
			)
			(layer "F.Fab")
		)
		(fp_line
			(start 0.120396 0.3048)
			(end 0.120396 0.2794)
			(stroke
				(width 0.1)
				(type default)
			)
			(layer "F.Fab")
		)
		(fp_line
			(start 0.67945 0.3048)
			(end 0.120396 0.3048)
			(stroke
				(width 0.1)
				(type default)
			)
			(layer "F.Fab")
		)
		(fp_line
			(start -0.12065 0.2794)
			(end -0.12065 0.3048)
			(stroke
				(width 0.1)
				(type default)
			)
			(layer "F.Fab")
		)
		(fp_line
			(start 0.120396 0.2794)
			(end -0.12065 0.2794)
			(stroke
				(width 0.1)
				(type default)
			)
			(layer "F.Fab")
		)
		(fp_line
			(start -0.12065 -0.2794)
			(end 0.12065 -0.2794)
			(stroke
				(width 0.1)
				(type default)
			)
			(layer "F.Fab")
		)
		(fp_line
			(start 0.12065 -0.2794)
			(end 0.12065 -0.3048)
			(stroke
				(width 0.1)
				(type default)
			)
			(layer "F.Fab")
		)
		(fp_line
			(start 0.12065 -0.3048)
			(end 0.67945 -0.3048)
			(stroke
				(width 0.1)
				(type default)
			)
			(layer "F.Fab")
		)
		(fp_line
			(start 0.67945 -0.3048)
			(end 0.67945 0.3048)
			(stroke
				(width 0.1)
				(type default)
			)
			(layer "F.Fab")
		)
		(fp_line
			(start -0.67945 -0.305054)
			(end -0.12065 -0.305054)
			(stroke
				(width 0.1)
				(type default)
			)
			(layer "F.Fab")
		)
		(fp_line
			(start -0.12065 -0.305054)
			(end -0.12065 -0.2794)
			(stroke
				(width 0.1)
				(type default)
			)
			(layer "F.Fab")
		)
		(pad "1" smd circle
			(at -0.40005 0 270)
			(size 0 0)
			(layers "F.Cu" "F.Mask" "F.Paste")
			(net "RST_CPU0_DRAM_CD_PLD_LVT3_R_N")
		)
		(pad "2" smd circle
			(at 0.40005 0 270)
			(size 0 0)
			(layers "F.Cu" "F.Mask" "F.Paste")
			(net "RST_CPU0_DRAM_CD_PLD_LVT3_N")
		)
	)
)
